(kicad_pcb
	(version 20260206)
	(generator "pcbnew")
	(generator_version "10.0")
	(general
		(thickness 1.6)
		(legacy_teardrops no)
	)
	(paper "A4")
	(title_block
		(title "01162023_DA0F0TEBIF0_F0T_Expander_BD_F_brd_V02_OCP.brd")
		(comment 1 "Grand Teton / footprints 8088-8093 of 9728")
	)
	(layers
		(0 "F.Cu" signal "TOP")
		(4 "In1.Cu" signal "GND")
		(6 "In2.Cu" signal "VCC")
		(8 "In3.Cu" signal "VCC1")
		(10 "In4.Cu" signal "GND1")
		(12 "In5.Cu" signal "IN1")
		(14 "In6.Cu" signal "GND2")
		(16 "In7.Cu" signal "IN2")
		(18 "In8.Cu" signal "GND3")
		(20 "In9.Cu" signal "IN3")
		(22 "In10.Cu" signal "GND4")
		(24 "In11.Cu" signal "IN4")
		(26 "In12.Cu" signal "GND5")
		(28 "In13.Cu" signal "IN5")
		(30 "In14.Cu" signal "GND6")
		(32 "In15.Cu" signal "IN6")
		(34 "In16.Cu" signal "GND7")
		(2 "B.Cu" signal "BOTTOM")
		(9 "F.Adhes" user "F.Adhesive")
		(11 "B.Adhes" user "B.Adhesive")
		(13 "F.Paste" user "Package Geometry/Pastemask Top")
		(15 "B.Paste" user "Package Geometry/Pastemask Bottom")
		(5 "F.SilkS" user "Ref Des/Silkscreen Top")
		(7 "B.SilkS" user "Ref Des/Silkscreen Bottom")
		(1 "F.Mask" user "Board Geometry/Soldermask Top")
		(3 "B.Mask" user "Board Geometry/Soldermask Bottom")
		(17 "Dwgs.User" user "User.Drawings")
		(19 "Cmts.User" user "User.Comments")
		(21 "Eco1.User" user "User.Eco1")
		(23 "Eco2.User" user "User.Eco2")
		(25 "Edge.Cuts" user "Board Geometry/Outline")
		(27 "Margin" user)
		(31 "F.CrtYd" user "Package Geometry/Place Bound Top")
		(29 "B.CrtYd" user "Package Geometry/Place Bound Bottom")
		(35 "F.Fab" user "Ref Des/Assembly Top")
		(33 "B.Fab" user "Ref Des/Assembly Bottom")
	)
	(footprint ""
		(layer "B.Cu")
		(at 305.490626 -246.199406 90)
		(property "Reference" "R4103"
			(at 0 0 90)
			(layer "B.SilkS")
			(hide yes)
			(effects
				(font
					(size 1.27 1.27)
				)
				(justify mirror)
			)
		)
		(property "Value" ""
			(at 0 0 90)
			(layer "B.Fab")
			(effects
				(font
					(size 1.27 1.27)
				)
				(justify mirror)
			)
		)
		(duplicate_pad_numbers_are_jumpers no)
		(fp_line
			(start 0.7874 -0.4064)
			(end -0.7874 -0.4064)
			(stroke
				(width 0.1524)
				(type default)
			)
			(layer "B.SilkS")
		)
		(fp_line
			(start -0.7874 -0.4064)
			(end -0.7874 0.4064)
			(stroke
				(width 0.1524)
				(type default)
			)
			(layer "B.SilkS")
		)
		(fp_line
			(start 0.7874 0.4064)
			(end 0.7874 -0.4064)
			(stroke
				(width 0.1524)
				(type default)
			)
			(layer "B.SilkS")
		)
		(fp_line
			(start -0.7874 0.4064)
			(end 0.7874 0.4064)
			(stroke
				(width 0.1524)
				(type default)
			)
			(layer "B.SilkS")
		)
		(fp_line
			(start 0.67945 -0.305054)
			(end 0.12065 -0.305054)
			(stroke
				(width 0.1)
				(type default)
			)
			(layer "B.Fab")
		)
		(fp_line
			(start 0.12065 -0.305054)
			(end 0.12065 -0.2794)
			(stroke
				(width 0.1)
				(type default)
			)
			(layer "B.Fab")
		)
		(fp_line
			(start -0.12065 -0.3048)
			(end -0.67945 -0.3048)
			(stroke
				(width 0.1)
				(type default)
			)
			(layer "B.Fab")
		)
		(fp_line
			(start -0.67945 -0.3048)
			(end -0.67945 0.3048)
			(stroke
				(width 0.1)
				(type default)
			)
			(layer "B.Fab")
		)
		(fp_line
			(start 0.12065 -0.2794)
			(end -0.12065 -0.2794)
			(stroke
				(width 0.1)
				(type default)
			)
			(layer "B.Fab")
		)
		(fp_line
			(start -0.12065 -0.2794)
			(end -0.12065 -0.3048)
			(stroke
				(width 0.1)
				(type default)
			)
			(layer "B.Fab")
		)
		(fp_line
			(start 0.12065 0.2794)
			(end 0.12065 0.3048)
			(stroke
				(width 0.1)
				(type default)
			)
			(layer "B.Fab")
		)
		(fp_line
			(start -0.120396 0.2794)
			(end 0.12065 0.2794)
			(stroke
				(width 0.1)
				(type default)
			)
			(layer "B.Fab")
		)
		(fp_line
			(start 0.67945 0.3048)
			(end 0.67945 -0.305054)
			(stroke
				(width 0.1)
				(type default)
			)
			(layer "B.Fab")
		)
		(fp_line
			(start 0.12065 0.3048)
			(end 0.67945 0.3048)
			(stroke
				(width 0.1)
				(type default)
			)
			(layer "B.Fab")
		)
		(fp_line
			(start -0.120396 0.3048)
			(end -0.120396 0.2794)
			(stroke
				(width 0.1)
				(type default)
			)
			(layer "B.Fab")
		)
		(fp_line
			(start -0.67945 0.3048)
			(end -0.120396 0.3048)
			(stroke
				(width 0.1)
				(type default)
			)
			(layer "B.Fab")
		)
		(pad "1" smd circle
			(at 0.40005 0 270)
			(size 0 0)
			(layers "B.Cu" "B.Mask" "B.Paste")
			(net "SMB_MB_BMC_R_SDA")
		)
		(pad "2" smd circle
			(at -0.40005 0 270)
			(size 0 0)
			(layers "B.Cu" "B.Mask" "B.Paste")
			(net "SMB_MB_BMC_ISO_SDA")
		)
	)
	(footprint ""
		(layer "B.Cu")
		(at 105.619042 -395.673834 90)
		(property "Reference" "R5442"
			(at 0 0 90)
			(layer "B.SilkS")
			(hide yes)
			(effects
				(font
					(size 1.27 1.27)
				)
				(justify mirror)
			)
		)
		(property "Value" ""
			(at 0 0 90)
			(layer "B.Fab")
			(effects
				(font
					(size 1.27 1.27)
				)
				(justify mirror)
			)
		)
		(duplicate_pad_numbers_are_jumpers no)
		(fp_line
			(start 0.7874 -0.4064)
			(end -0.7874 -0.4064)
			(stroke
				(width 0.1524)
				(type default)
			)
			(layer "B.SilkS")
		)
		(fp_line
			(start -0.7874 -0.4064)
			(end -0.7874 0.4064)
			(stroke
				(width 0.1524)
				(type default)
			)
			(layer "B.SilkS")
		)
		(fp_line
			(start 0.7874 0.4064)
			(end 0.7874 -0.4064)
			(stroke
				(width 0.1524)
				(type default)
			)
			(layer "B.SilkS")
		)
		(fp_line
			(start -0.7874 0.4064)
			(end 0.7874 0.4064)
			(stroke
				(width 0.1524)
				(type default)
			)
			(layer "B.SilkS")
		)
		(fp_line
			(start 0.67945 -0.305054)
			(end 0.12065 -0.305054)
			(stroke
				(width 0.1)
				(type default)
			)
			(layer "B.Fab")
		)
		(fp_line
			(start 0.12065 -0.305054)
			(end 0.12065 -0.2794)
			(stroke
				(width 0.1)
				(type default)
			)
			(layer "B.Fab")
		)
		(fp_line
			(start -0.12065 -0.3048)
			(end -0.67945 -0.3048)
			(stroke
				(width 0.1)
				(type default)
			)
			(layer "B.Fab")
		)
		(fp_line
			(start -0.67945 -0.3048)
			(end -0.67945 0.3048)
			(stroke
				(width 0.1)
				(type default)
			)
			(layer "B.Fab")
		)
		(fp_line
			(start 0.12065 -0.2794)
			(end -0.12065 -0.2794)
			(stroke
				(width 0.1)
				(type default)
			)
			(layer "B.Fab")
		)
		(fp_line
			(start -0.12065 -0.2794)
			(end -0.12065 -0.3048)
			(stroke
				(width 0.1)
				(type default)
			)
			(layer "B.Fab")
		)
		(fp_line
			(start 0.12065 0.2794)
			(end 0.12065 0.3048)
			(stroke
				(width 0.1)
				(type default)
			)
			(layer "B.Fab")
		)
		(fp_line
			(start -0.120396 0.2794)
			(end 0.12065 0.2794)
			(stroke
				(width 0.1)
				(type default)
			)
			(layer "B.Fab")
		)
		(fp_line
			(start 0.67945 0.3048)
			(end 0.67945 -0.305054)
			(stroke
				(width 0.1)
				(type default)
			)
			(layer "B.Fab")
		)
		(fp_line
			(start 0.12065 0.3048)
			(end 0.67945 0.3048)
			(stroke
				(width 0.1)
				(type default)
			)
			(layer "B.Fab")
		)
		(fp_line
			(start -0.120396 0.3048)
			(end -0.120396 0.2794)
			(stroke
				(width 0.1)
				(type default)
			)
			(layer "B.Fab")
		)
		(fp_line
			(start -0.67945 0.3048)
			(end -0.120396 0.3048)
			(stroke
				(width 0.1)
				(type default)
			)
			(layer "B.Fab")
		)
		(pad "1" smd circle
			(at 0.40005 0 270)
			(size 0 0)
			(layers "B.Cu" "B.Mask" "B.Paste")
			(net "P3V3_AUX")
		)
		(pad "2" smd circle
			(at -0.40005 0 270)
			(size 0 0)
			(layers "B.Cu" "B.Mask" "B.Paste")
			(net "P3V3_BIC_USB_HUB")
		)
	)
	(footprint ""
		(layer "B.Cu")
		(at 378.079 -239.014 -90)
		(property "Reference" "C2564"
			(at 0 0 90)
			(layer "B.SilkS")
			(hide yes)
			(effects
				(font
					(size 1.27 1.27)
				)
				(justify mirror)
			)
		)
		(property "Value" ""
			(at 0 0 90)
			(layer "B.Fab")
			(effects
				(font
					(size 1.27 1.27)
				)
				(justify mirror)
			)
		)
		(duplicate_pad_numbers_are_jumpers no)
		(fp_line
			(start -1.2954 0.5842)
			(end 1.2954 0.5842)
			(stroke
				(width 0.1524)
				(type default)
			)
			(layer "B.SilkS")
		)
		(fp_line
			(start 1.2954 0.5842)
			(end 1.2954 -0.5842)
			(stroke
				(width 0.1524)
				(type default)
			)
			(layer "B.SilkS")
		)
		(fp_line
			(start -1.2954 -0.5842)
			(end -1.2954 0.5842)
			(stroke
				(width 0.1524)
				(type default)
			)
			(layer "B.SilkS")
		)
		(fp_line
			(start 1.2954 -0.5842)
			(end -1.2954 -0.5842)
			(stroke
				(width 0.1524)
				(type default)
			)
			(layer "B.SilkS")
		)
		(fp_line
			(start -0.8636 0.4572)
			(end 0.8636 0.4572)
			(stroke
				(width 0.1)
				(type default)
			)
			(layer "B.Fab")
		)
		(fp_line
			(start 0.8636 0.4572)
			(end 0.8636 0.4064)
			(stroke
				(width 0.1)
				(type default)
			)
			(layer "B.Fab")
		)
		(fp_line
			(start -1.1938 0.4064)
			(end -0.8636 0.4064)
			(stroke
				(width 0.1)
				(type default)
			)
			(layer "B.Fab")
		)
		(fp_line
			(start -0.8636 0.4064)
			(end -0.8636 0.4572)
			(stroke
				(width 0.1)
				(type default)
			)
			(layer "B.Fab")
		)
		(fp_line
			(start 0.8636 0.4064)
			(end 1.1938 0.4064)
			(stroke
				(width 0.1)
				(type default)
			)
			(layer "B.Fab")
		)
		(fp_line
			(start 1.1938 0.4064)
			(end 1.1938 -0.4064)
			(stroke
				(width 0.1)
				(type default)
			)
			(layer "B.Fab")
		)
		(fp_line
			(start -1.1938 -0.4064)
			(end -1.1938 0.4064)
			(stroke
				(width 0.1)
				(type default)
			)
			(layer "B.Fab")
		)
		(fp_line
			(start -0.8636 -0.4064)
			(end -1.1938 -0.4064)
			(stroke
				(width 0.1)
				(type default)
			)
			(layer "B.Fab")
		)
		(fp_line
			(start 0.8636 -0.4064)
			(end 0.8636 -0.4572)
			(stroke
				(width 0.1)
				(type default)
			)
			(layer "B.Fab")
		)
		(fp_line
			(start 1.1938 -0.4064)
			(end 0.8636 -0.4064)
			(stroke
				(width 0.1)
				(type default)
			)
			(layer "B.Fab")
		)
		(fp_line
			(start -0.8636 -0.4572)
			(end -0.8636 -0.4064)
			(stroke
				(width 0.1)
				(type default)
			)
			(layer "B.Fab")
		)
		(fp_line
			(start 0.8636 -0.4572)
			(end -0.8636 -0.4572)
			(stroke
				(width 0.1)
				(type default)
			)
			(layer "B.Fab")
		)
		(pad "1" smd rect
			(at 0.7366 0 180)
			(size 0.7112 0.8128)
			(layers "B.Cu" "B.Mask" "B.Paste")
			(net "P3V3_AUX")
		)
		(pad "2" smd rect
			(at -0.7366 0 180)
			(size 0.7112 0.8128)
			(layers "B.Cu" "B.Mask" "B.Paste")
			(net "GND")
		)
	)
	(footprint ""
		(layer "B.Cu")
		(at 122.809254 -325.186294 -90)
		(property "Reference" "C4271"
			(at 0 0 90)
			(layer "B.SilkS")
			(hide yes)
			(effects
				(font
					(size 1.27 1.27)
				)
				(justify mirror)
			)
		)
		(property "Value" ""
			(at 0 0 90)
			(layer "B.Fab")
			(effects
				(font
					(size 1.27 1.27)
				)
				(justify mirror)
			)
		)
		(duplicate_pad_numbers_are_jumpers no)
		(fp_line
			(start -1.2954 0.5842)
			(end 1.2954 0.5842)
			(stroke
				(width 0.1524)
				(type default)
			)
			(layer "B.SilkS")
		)
		(fp_line
			(start 1.2954 0.5842)
			(end 1.2954 -0.5842)
			(stroke
				(width 0.1524)
				(type default)
			)
			(layer "B.SilkS")
		)
		(fp_line
			(start -1.2954 -0.5842)
			(end -1.2954 0.5842)
			(stroke
				(width 0.1524)
				(type default)
			)
			(layer "B.SilkS")
		)
		(fp_line
			(start 1.2954 -0.5842)
			(end -1.2954 -0.5842)
			(stroke
				(width 0.1524)
				(type default)
			)
			(layer "B.SilkS")
		)
		(fp_line
			(start -0.8636 0.4572)
			(end 0.8636 0.4572)
			(stroke
				(width 0.1)
				(type default)
			)
			(layer "B.Fab")
		)
		(fp_line
			(start 0.8636 0.4572)
			(end 0.8636 0.4064)
			(stroke
				(width 0.1)
				(type default)
			)
			(layer "B.Fab")
		)
		(fp_line
			(start -1.1938 0.4064)
			(end -0.8636 0.4064)
			(stroke
				(width 0.1)
				(type default)
			)
			(layer "B.Fab")
		)
		(fp_line
			(start -0.8636 0.4064)
			(end -0.8636 0.4572)
			(stroke
				(width 0.1)
				(type default)
			)
			(layer "B.Fab")
		)
		(fp_line
			(start 0.8636 0.4064)
			(end 1.1938 0.4064)
			(stroke
				(width 0.1)
				(type default)
			)
			(layer "B.Fab")
		)
		(fp_line
			(start 1.1938 0.4064)
			(end 1.1938 -0.4064)
			(stroke
				(width 0.1)
				(type default)
			)
			(layer "B.Fab")
		)
		(fp_line
			(start -1.1938 -0.4064)
			(end -1.1938 0.4064)
			(stroke
				(width 0.1)
				(type default)
			)
			(layer "B.Fab")
		)
		(fp_line
			(start -0.8636 -0.4064)
			(end -1.1938 -0.4064)
			(stroke
				(width 0.1)
				(type default)
			)
			(layer "B.Fab")
		)
		(fp_line
			(start 0.8636 -0.4064)
			(end 0.8636 -0.4572)
			(stroke
				(width 0.1)
				(type default)
			)
			(layer "B.Fab")
		)
		(fp_line
			(start 1.1938 -0.4064)
			(end 0.8636 -0.4064)
			(stroke
				(width 0.1)
				(type default)
			)
			(layer "B.Fab")
		)
		(fp_line
			(start -0.8636 -0.4572)
			(end -0.8636 -0.4064)
			(stroke
				(width 0.1)
				(type default)
			)
			(layer "B.Fab")
		)
		(fp_line
			(start 0.8636 -0.4572)
			(end -0.8636 -0.4572)
			(stroke
				(width 0.1)
				(type default)
			)
			(layer "B.Fab")
		)
		(pad "1" smd rect
			(at 0.7366 0 180)
			(size 0.7112 0.8128)
			(layers "B.Cu" "B.Mask" "B.Paste")
			(net "P0V8_SERDES_VDDA_PEX1_C9")
		)
		(pad "2" smd rect
			(at -0.7366 0 180)
			(size 0.7112 0.8128)
			(layers "B.Cu" "B.Mask" "B.Paste")
			(net "GND")
		)
	)
	(footprint ""
		(layer "B.Cu")
		(at 217.235786 -219.318586)
		(property "Reference" "R1495"
			(at 0 0 0)
			(layer "B.SilkS")
			(hide yes)
			(effects
				(font
					(size 1.27 1.27)
				)
				(justify mirror)
			)
		)
		(property "Value" ""
			(at 0 0 0)
			(layer "B.Fab")
			(effects
				(font
					(size 1.27 1.27)
				)
				(justify mirror)
			)
		)
		(duplicate_pad_numbers_are_jumpers no)
		(fp_line
			(start -0.7874 -0.4064)
			(end -0.7874 0.4064)
			(stroke
				(width 0.1524)
				(type default)
			)
			(layer "B.SilkS")
		)
		(fp_line
			(start -0.7874 0.4064)
			(end 0.7874 0.4064)
			(stroke
				(width 0.1524)
				(type default)
			)
			(layer "B.SilkS")
		)
		(fp_line
			(start 0.7874 -0.4064)
			(end -0.7874 -0.4064)
			(stroke
				(width 0.1524)
				(type default)
			)
			(layer "B.SilkS")
		)
		(fp_line
			(start 0.7874 0.4064)
			(end 0.7874 -0.4064)
			(stroke
				(width 0.1524)
				(type default)
			)
			(layer "B.SilkS")
		)
		(fp_line
			(start -0.67945 -0.3048)
			(end -0.67945 0.3048)
			(stroke
				(width 0.1)
				(type default)
			)
			(layer "B.Fab")
		)
		(fp_line
			(start -0.67945 0.3048)
			(end -0.120396 0.3048)
			(stroke
				(width 0.1)
				(type default)
			)
			(layer "B.Fab")
		)
		(fp_line
			(start -0.12065 -0.3048)
			(end -0.67945 -0.3048)
			(stroke
				(width 0.1)
				(type default)
			)
			(layer "B.Fab")
		)
		(fp_line
			(start -0.12065 -0.2794)
			(end -0.12065 -0.3048)
			(stroke
				(width 0.1)
				(type default)
			)
			(layer "B.Fab")
		)
		(fp_line
			(start -0.120396 0.2794)
			(end 0.12065 0.2794)
			(stroke
				(width 0.1)
				(type default)
			)
			(layer "B.Fab")
		)
		(fp_line
			(start -0.120396 0.3048)
			(end -0.120396 0.2794)
			(stroke
				(width 0.1)
				(type default)
			)
			(layer "B.Fab")
		)
		(fp_line
			(start 0.12065 -0.305054)
			(end 0.12065 -0.2794)
			(stroke
				(width 0.1)
				(type default)
			)
			(layer "B.Fab")
		)
		(fp_line
			(start 0.12065 -0.2794)
			(end -0.12065 -0.2794)
			(stroke
				(width 0.1)
				(type default)
			)
			(layer "B.Fab")
		)
		(fp_line
			(start 0.12065 0.2794)
			(end 0.12065 0.3048)
			(stroke
				(width 0.1)
				(type default)
			)
			(layer "B.Fab")
		)
		(fp_line
			(start 0.12065 0.3048)
			(end 0.67945 0.3048)
			(stroke
				(width 0.1)
				(type default)
			)
			(layer "B.Fab")
		)
		(fp_line
			(start 0.67945 -0.305054)
			(end 0.12065 -0.305054)
			(stroke
				(width 0.1)
				(type default)
			)
			(layer "B.Fab")
		)
		(fp_line
			(start 0.67945 0.3048)
			(end 0.67945 -0.305054)
			(stroke
				(width 0.1)
				(type default)
			)
			(layer "B.Fab")
		)
		(pad "1" smd circle
			(at 0.40005 0 180)
			(size 0 0)
			(layers "B.Cu" "B.Mask" "B.Paste")
			(net "SMB_PEX_SCL")
		)
		(pad "2" smd circle
			(at -0.40005 0 180)
			(size 0 0)
			(layers "B.Cu" "B.Mask" "B.Paste")
			(net "SMB_PEX_R_SCL")
		)
	)
	(footprint ""
		(layer "B.Cu")
		(at 3.079242 -271.930368)
		(property "Reference" "C4219"
			(at 0 0 0)
			(layer "B.SilkS")
			(hide yes)
			(effects
				(font
					(size 1.27 1.27)
				)
				(justify mirror)
			)
		)
		(property "Value" ""
			(at 0 0 0)
			(layer "B.Fab")
			(effects
				(font
					(size 1.27 1.27)
				)
				(justify mirror)
			)
		)
		(duplicate_pad_numbers_are_jumpers no)
		(fp_line
			(start -1.2954 -0.5842)
			(end -1.2954 0.5842)
			(stroke
				(width 0.1524)
				(type default)
			)
			(layer "B.SilkS")
		)
		(fp_line
			(start -1.2954 0.5842)
			(end 1.2954 0.5842)
			(stroke
				(width 0.1524)
				(type default)
			)
			(layer "B.SilkS")
		)
		(fp_line
			(start 1.2954 -0.5842)
			(end -1.2954 -0.5842)
			(stroke
				(width 0.1524)
				(type default)
			)
			(layer "B.SilkS")
		)
		(fp_line
			(start 1.2954 0.5842)
			(end 1.2954 -0.5842)
			(stroke
				(width 0.1524)
				(type default)
			)
			(layer "B.SilkS")
		)
		(fp_line
			(start -1.1938 -0.4064)
			(end -1.1938 0.4064)
			(stroke
				(width 0.1)
				(type default)
			)
			(layer "B.Fab")
		)
		(fp_line
			(start -1.1938 0.4064)
			(end -0.8636 0.4064)
			(stroke
				(width 0.1)
				(type default)
			)
			(layer "B.Fab")
		)
		(fp_line
			(start -0.8636 -0.4572)
			(end -0.8636 -0.4064)
			(stroke
				(width 0.1)
				(type default)
			)
			(layer "B.Fab")
		)
		(fp_line
			(start -0.8636 -0.4064)
			(end -1.1938 -0.4064)
			(stroke
				(width 0.1)
				(type default)
			)
			(layer "B.Fab")
		)
		(fp_line
			(start -0.8636 0.4064)
			(end -0.8636 0.4572)
			(stroke
				(width 0.1)
				(type default)
			)
			(layer "B.Fab")
		)
		(fp_line
			(start -0.8636 0.4572)
			(end 0.8636 0.4572)
			(stroke
				(width 0.1)
				(type default)
			)
			(layer "B.Fab")
		)
		(fp_line
			(start 0.8636 -0.4572)
			(end -0.8636 -0.4572)
			(stroke
				(width 0.1)
				(type default)
			)
			(layer "B.Fab")
		)
		(fp_line
			(start 0.8636 -0.4064)
			(end 0.8636 -0.4572)
			(stroke
				(width 0.1)
				(type default)
			)
			(layer "B.Fab")
		)
		(fp_line
			(start 0.8636 0.4064)
			(end 1.1938 0.4064)
			(stroke
				(width 0.1)
				(type default)
			)
			(layer "B.Fab")
		)
		(fp_line
			(start 0.8636 0.4572)
			(end 0.8636 0.4064)
			(stroke
				(width 0.1)
				(type default)
			)
			(layer "B.Fab")
		)
		(fp_line
			(start 1.1938 -0.4064)
			(end 0.8636 -0.4064)
			(stroke
				(width 0.1)
				(type default)
			)
			(layer "B.Fab")
		)
		(fp_line
			(start 1.1938 0.4064)
			(end 1.1938 -0.4064)
			(stroke
				(width 0.1)
				(type default)
			)
			(layer "B.Fab")
		)
		(pad "1" smd rect
			(at 0.7366 0 270)
			(size 0.7112 0.8128)
			(layers "B.Cu" "B.Mask" "B.Paste")
			(net "P1V25_PEX0")
		)
		(pad "2" smd rect
			(at -0.7366 0 270)
			(size 0.7112 0.8128)
			(layers "B.Cu" "B.Mask" "B.Paste")
			(net "GND")
		)
	)
)
